FILE_TYPE=LIBRARY_PARTS;
primitive '74LVC1G66GV';
  pin
    'Y':
      PIN_NUMBER='(1)';
      BIDIRECTIONAL='TRUE';
      INPUT_LOAD='(-0.01,0.01)';
      OUTPUT_LOAD='(1.0,-1.0)';
    'Z':
      PIN_NUMBER='(2)';
      BIDIRECTIONAL='TRUE';
      INPUT_LOAD='(-0.01,0.01)';
      OUTPUT_LOAD='(1.0,-1.0)';
    'GND':
      PIN_NUMBER='(3)';
      PINUSE='POWER';
      NO_LOAD_CHECK='Both';
      NO_IO_CHECK='Both';
      NO_ASSERT_CHECK='TRUE';
      NO_DIR_CHECK='TRUE';
      ALLOW_CONNECT='TRUE';
    'E':
      PIN_NUMBER='(4)';
      INPUT_LOAD='(-0.01,0.01)';
    'VCC':
      PIN_NUMBER='(5)';
      PINUSE='POWER';
      NO_LOAD_CHECK='Both';
      NO_IO_CHECK='Both';
      NO_ASSERT_CHECK='TRUE';
      NO_DIR_CHECK='TRUE';
      ALLOW_CONNECT='TRUE';
  end_pin;
  body
    PART_NAME='74LVC1G66GV';
    BODY_NAME='74LVC1G66GV';
    PHYS_DES_PREFIX='U';
    CLASS='IC';
  end_body;
end_primitive;

END.
